FILE_TYPE = MACRO_DRAWING;
SET COLOR_WIRE YELLOW;
SET COLOR_PROP ORANGE;
SET COLOR_DOT WHITE;
SET COLOR_ARC YELLOW;
SET COLOR_BODY GREEN;
SET COLOR_NOTE PURPLE;
SET PROP_DISPLAY VALUE;
SET PAGE_NUMBER P124;
FORCEADD QUANTA_TITLE_BLOCK_C..1
(9700 1125);
FORCEPROP 1 LAST CUSTOM_TXT_CDS <NAME_2>
J 0
(6525 1175);
FORCEPROP 1 LAST CUSTOM_TXT_CDS <NAME_1>
J 0
(6525 1300);
FORCEPROP 1 LAST CUSTOM_TXT_CDS <Q_NUMBER>
J 0
(8297 1228);
DISPLAY 1.212766 (8297 1228);
FORCEPROP 1 LAST CUSTOM_TXT_CDS <Q_PROJ>
J 0
(7318 1227);
DISPLAY 1.212766 (7318 1227);
FORCEPROP 1 LAST CUSTOM_TXT_CDS <Q_REV>
J 0
(9516 1228);
DISPLAY 1.212766 (9516 1228);
FORCEPROP 1 LAST CUSTOM_TXT_CDS <CON_LAST_MODIFIED>
J 0
(7815 1140);
DISPLAY 0.978723 (7815 1140);
FORCEPROP 1 LAST CUSTOM_TXT_CDS <CON_PAGE_NUM> OF <CON_TOTAL_PAGES>
J 0
(9254 1143);
DISPLAY 0.978723 (9254 1143);
FORCEPROP 1 LAST Q_DEPT BU9
J 1
(5937 1174);
DISPLAY 1.957447 (5937 1174);
PAINT GREEN (5937 1174);
FORCEPROP 1 LAST Q_TITLE E1.S CONN1
J 0
(425 1200);
DISPLAY 2.446809 (425 1200);
PAINT GREEN (425 1200);
FORCEPROP 1 LAST COMMENT_BODY TRUE
J 0
(9712 1112);
DISPLAY 0.978723 (9712 1112);
PAINT GREEN (9712 1112);
DISPLAY INVISIBLE (9712 1112);
FORCEPROP 2 LAST PAGE_BORDER TRUE
J 0
(1810 6375);
DISPLAY 0.638298 (1810 6375);
PAINT PINK (1810 6375);
DISPLAY INVISIBLE (1810 6375);
FORCEPROP 1 LAST CDS_LMAN_SYM_OUTLINE -9475,6775,100,-125
J 0
(9700 1125);
DISPLAY 0.468085 (9700 1125);
PAINT GREEN (9700 1125);
DISPLAY INVISIBLE (9700 1125);
FORCEPROP 2 LAST CDS_LIB pure_quanta
J 0
(9700 1125);
DISPLAY INVISIBLE (9700 1125);
FORCEPROP 2 LAST CDS_XR_PAGE_TITLE CR-124 : @T6G_MB_LIB.T6G(SCH_1):PAGE124
J 0
(1810 6375);
DISPLAY 0.638298 (1810 6375);
PAINT PINK (1810 6375);
DISPLAY INVISIBLE (1810 6375);
FORCEPROP 2 LAST CUSTOM_TXT_CDS <XR_PAGE_TITLE>
J 0
(1810 6375);
DISPLAY 0.638298 (1810 6375);
PAINT PINK (1810 6375);
DISPLAY INVISIBLE (1810 6375);
FORCEPROP 0 LAST CDS_CON_LAST_MODIFIED Wed Mar 09 18:12:32 2022
J 0
(7815 1140);
DISPLAY INVISIBLE (7815 1140);
QUIT
